(kicad_pcb
	(version 20260206)
	(generator "pcbnew")
	(generator_version "10.0")
	(general
		(thickness 1.6)
		(legacy_teardrops no)
	)
	(paper "A4")
	(title_block
		(title "Wiwynn_Tioga_Pass_MB.brd")
		(comment 1 "Tioga Pass / footprints 3594-3600 of 4770")
	)
	(layers
		(0 "F.Cu" signal "TOP")
		(4 "In1.Cu" signal "L2GND")
		(6 "In2.Cu" signal "L3")
		(8 "In3.Cu" signal "L4GND")
		(10 "In4.Cu" signal "L5")
		(12 "In5.Cu" signal "L6GND")
		(14 "In6.Cu" signal "L7VCC")
		(16 "In7.Cu" signal "L8VCC")
		(18 "In8.Cu" signal "L9GND")
		(20 "In9.Cu" signal "L10")
		(22 "In10.Cu" signal "L11GND")
		(24 "In11.Cu" signal "L12")
		(26 "In12.Cu" signal "L13GND")
		(2 "B.Cu" signal "BOTTOM")
		(9 "F.Adhes" user "F.Adhesive")
		(11 "B.Adhes" user "B.Adhesive")
		(13 "F.Paste" user "Package Geometry/Pastemask Top")
		(15 "B.Paste" user "Package Geometry/Pastemask Bottom")
		(5 "F.SilkS" user "Ref Des/Silkscreen Top")
		(7 "B.SilkS" user "Ref Des/Silkscreen Bottom")
		(1 "F.Mask" user "Board Geometry/Soldermask Top")
		(3 "B.Mask" user "Board Geometry/Soldermask Bottom")
		(17 "Dwgs.User" user "User.Drawings")
		(19 "Cmts.User" user "User.Comments")
		(21 "Eco1.User" user "User.Eco1")
		(23 "Eco2.User" user "User.Eco2")
		(25 "Edge.Cuts" user "Board Geometry/Outline")
		(27 "Margin" user)
		(31 "F.CrtYd" user "Package Geometry/Place Bound Top")
		(29 "B.CrtYd" user "Package Geometry/Place Bound Bottom")
		(35 "F.Fab" user "Ref Des/Assembly Top")
		(33 "B.Fab" user "Ref Des/Assembly Bottom")
	)
	(footprint ""
		(layer "B.Cu")
		(at 444.548006 -41.648126 180)
		(property "Reference" "R25W18"
			(at 0 0 0)
			(layer "B.SilkS")
			(hide yes)
			(effects
				(font
					(size 1.27 1.27)
				)
				(justify mirror)
			)
		)
		(property "Value" "*"
			(at -0.064008 -4.108196 180)
			(unlocked yes)
			(layer "B.Fab")
			(hide yes)
			(effects
				(font
					(size 1.27 1.016)
					(thickness 0.1524)
				)
				(justify mirror)
			)
		)
		(property "Device Type" "120R2F-GP_RCL_GP-120R2F-GP,64.A"
			(at -0.064008 -5.632196 180)
			(unlocked yes)
			(layer "B.Fab")
			(hide yes)
			(effects
				(font
					(size 1.27 1.016)
					(thickness 0.1524)
				)
				(justify mirror)
			)
		)
		(duplicate_pad_numbers_are_jumpers no)
		(fp_line
			(start 0.508 -0.9398)
			(end 0.508 0.9398)
			(stroke
				(width 0.1524)
				(type default)
			)
			(layer "B.SilkS")
		)
		(fp_line
			(start -0.508 -0.9398)
			(end 0.508 -0.9398)
			(stroke
				(width 0.1524)
				(type default)
			)
			(layer "B.SilkS")
		)
		(fp_rect
			(start 0.508 0.9398)
			(end -0.508 -0.9398)
			(stroke
				(width 0)
				(type default)
			)
			(fill no)
			(layer "B.CrtYd")
		)
		(fp_rect
			(start 0.508 0.9398)
			(end -0.508 -0.9398)
			(stroke
				(width 0)
				(type default)
			)
			(fill no)
			(layer "B.Fab")
		)
		(pad "1" smd custom
			(at 0 -0.4445)
			(size 0.1397 0.1397)
			(layers "B.Cu" "B.Mask" "B.Paste")
			(net "GND")
			(options
				(clearance outline)
				(anchor circle)
			)
			(primitives
				(gr_poly
					(pts
						(arc
							(start -0.1778 0.2794)
							(mid -0.249642 0.249642)
							(end -0.2794 0.1778)
						)
						(arc
							(start -0.2794 -0.1778)
							(mid -0.249642 -0.249642)
							(end -0.1778 -0.2794)
						)
						(arc
							(start 0.1778 -0.2794)
							(mid 0.249642 -0.249642)
							(end 0.2794 -0.1778)
						)
						(arc
							(start 0.2794 0.1778)
							(mid 0.249642 0.249642)
							(end 0.1778 0.2794)
						)
					)
					(width 0)
					(fill yes)
				)
			)
		)
		(pad "2" smd custom
			(at 0 0.4445)
			(size 0.1397 0.1397)
			(layers "B.Cu" "B.Mask" "B.Paste")
			(net "BMC_M_A6")
			(options
				(clearance outline)
				(anchor circle)
			)
			(primitives
				(gr_poly
					(pts
						(arc
							(start -0.1778 0.2794)
							(mid -0.249642 0.249642)
							(end -0.2794 0.1778)
						)
						(arc
							(start -0.2794 -0.1778)
							(mid -0.249642 -0.249642)
							(end -0.1778 -0.2794)
						)
						(arc
							(start 0.1778 -0.2794)
							(mid 0.249642 -0.249642)
							(end 0.2794 -0.1778)
						)
						(arc
							(start 0.2794 0.1778)
							(mid 0.249642 0.249642)
							(end 0.1778 0.2794)
						)
					)
					(width 0)
					(fill yes)
				)
			)
		)
	)
	(footprint ""
		(layer "B.Cu")
		(at 197.226428 -95.171006 90)
		(property "Reference" "R6N3"
			(at 0 0 90)
			(layer "B.SilkS")
			(hide yes)
			(effects
				(font
					(size 1.27 1.27)
				)
				(justify mirror)
			)
		)
		(property "Value" ""
			(at 0 0 90)
			(layer "B.Fab")
			(effects
				(font
					(size 1.27 1.27)
				)
				(justify mirror)
			)
		)
		(duplicate_pad_numbers_are_jumpers no)
		(fp_rect
			(start 0.2794 -0.1016)
			(end -0.2794 0.9906)
			(stroke
				(width 0)
				(type default)
			)
			(fill no)
			(layer "B.CrtYd")
		)
		(fp_line
			(start 0.2794 -0.1016)
			(end 0.2794 0.9906)
			(stroke
				(width 0.1)
				(type default)
			)
			(layer "B.Fab")
		)
		(fp_line
			(start -0.2794 -0.1016)
			(end 0.2794 -0.1016)
			(stroke
				(width 0.1)
				(type default)
			)
			(layer "B.Fab")
		)
		(fp_line
			(start 0.2794 0.9906)
			(end -0.2794 0.9906)
			(stroke
				(width 0.1)
				(type default)
			)
			(layer "B.Fab")
		)
		(fp_line
			(start -0.2794 0.9906)
			(end -0.2794 -0.1016)
			(stroke
				(width 0.1)
				(type default)
			)
			(layer "B.Fab")
		)
		(pad "1" smd rect
			(at 0 0 270)
			(size 0.508 0.508)
			(layers "B.Cu" "B.Mask" "B.Paste")
			(net "VR_PVSA_CPU0_VCIN")
		)
		(pad "2" smd rect
			(at 0 0.889 270)
			(size 0.508 0.508)
			(layers "B.Cu" "B.Mask" "B.Paste")
			(net "P5V_STBY")
		)
		(zone
			(layer "B.Cu")
			(hatch none 0.5)
			(connect_pads
				(clearance 0)
			)
			(min_thickness 0.25)
			(keepout
				(tracks not_allowed)
				(vias allowed)
				(pads allowed)
				(copperpour not_allowed)
				(footprints allowed)
			)
			(placement
				(enabled no)
				(sheetname "")
			)
			(fill
				(thermal_gap 0.5)
				(thermal_bridge_width 0.5)
				(island_removal_mode 0)
			)
			(polygon
				(pts
					(xy 197.480428 -95.425006) (xy 197.480428 -94.917006) (xy 197.861428 -94.917006) (xy 197.861428 -95.425006)
				)
			)
		)
		(zone
			(layer "B.Cu")
			(hatch none 0.5)
			(connect_pads
				(clearance 0)
			)
			(min_thickness 0.25)
			(keepout
				(tracks allowed)
				(vias not_allowed)
				(pads allowed)
				(copperpour not_allowed)
				(footprints allowed)
			)
			(placement
				(enabled no)
				(sheetname "")
			)
			(fill
				(thermal_gap 0.5)
				(thermal_bridge_width 0.5)
				(island_removal_mode 0)
			)
			(polygon
				(pts
					(xy 197.480428 -95.425006) (xy 197.480428 -94.917006) (xy 197.861428 -94.917006) (xy 197.861428 -95.425006)
				)
			)
		)
	)
	(footprint ""
		(layer "B.Cu")
		(at 40.936418 -103.482648 90)
		(property "Reference" "R1C12"
			(at 0.8382 -0.67818 90)
			(unlocked yes)
			(layer "B.SilkS")
			(effects
				(font
					(size 0.4064 0.254)
					(thickness 0.1524)
				)
				(justify left mirror)
			)
		)
		(property "Value" ""
			(at 0 0 90)
			(layer "B.Fab")
			(effects
				(font
					(size 1.27 1.27)
				)
				(justify mirror)
			)
		)
		(duplicate_pad_numbers_are_jumpers no)
		(fp_poly
			(pts
				(xy 0.2794 -0.1016) (xy -0.2794 -0.1016) (xy -0.2794 0.9906) (xy 0.2794 0.9906)
			)
			(stroke
				(width 0)
				(type default)
			)
			(fill no)
			(layer "B.CrtYd")
		)
		(fp_line
			(start 0.2794 -0.1016)
			(end 0.2794 0.9906)
			(stroke
				(width 0.1)
				(type default)
			)
			(layer "B.Fab")
		)
		(fp_line
			(start -0.2794 -0.1016)
			(end 0.2794 -0.1016)
			(stroke
				(width 0.1)
				(type default)
			)
			(layer "B.Fab")
		)
		(fp_line
			(start 0.2794 0.9906)
			(end -0.2794 0.9906)
			(stroke
				(width 0.1)
				(type default)
			)
			(layer "B.Fab")
		)
		(fp_line
			(start -0.2794 0.9906)
			(end -0.2794 -0.1016)
			(stroke
				(width 0.1)
				(type default)
			)
			(layer "B.Fab")
		)
		(pad "1" smd rect
			(at 0 0 270)
			(size 0.508 0.508)
			(layers "B.Cu" "B.Mask" "B.Paste")
			(net "VSENSE_PVSA_CPU1_P")
		)
		(pad "2" smd rect
			(at 0 0.889 270)
			(size 0.508 0.508)
			(layers "B.Cu" "B.Mask" "B.Paste")
			(net "PVSA_CPU1")
		)
		(zone
			(layer "B.Cu")
			(hatch none 0.5)
			(connect_pads
				(clearance 0)
			)
			(min_thickness 0.25)
			(keepout
				(tracks allowed)
				(vias not_allowed)
				(pads allowed)
				(copperpour not_allowed)
				(footprints allowed)
			)
			(placement
				(enabled no)
				(sheetname "")
			)
			(fill
				(thermal_gap 0.5)
				(thermal_bridge_width 0.5)
				(island_removal_mode 0)
			)
			(polygon
				(pts
					(xy 41.190418 -103.736648) (xy 41.190418 -103.228648) (xy 41.571418 -103.228648) (xy 41.571418 -103.736648)
				)
			)
		)
		(zone
			(layer "B.Cu")
			(hatch none 0.5)
			(connect_pads
				(clearance 0)
			)
			(min_thickness 0.25)
			(keepout
				(tracks not_allowed)
				(vias allowed)
				(pads allowed)
				(copperpour not_allowed)
				(footprints allowed)
			)
			(placement
				(enabled no)
				(sheetname "")
			)
			(fill
				(thermal_gap 0.5)
				(thermal_bridge_width 0.5)
				(island_removal_mode 0)
			)
			(polygon
				(pts
					(xy 41.571418 -103.736648) (xy 41.571418 -103.228648) (xy 41.190418 -103.228648) (xy 41.190418 -103.736648)
				)
			)
		)
	)
	(footprint ""
		(layer "B.Cu")
		(at 386.08 -87.3125 180)
		(property "Reference" "R3N10"
			(at 0 0 0)
			(layer "B.SilkS")
			(hide yes)
			(effects
				(font
					(size 1.27 1.27)
				)
				(justify mirror)
			)
		)
		(property "Value" ""
			(at 0 0 0)
			(layer "B.Fab")
			(effects
				(font
					(size 1.27 1.27)
				)
				(justify mirror)
			)
		)
		(duplicate_pad_numbers_are_jumpers no)
		(fp_poly
			(pts
				(xy 0.2794 -0.1016) (xy -0.2794 -0.1016) (xy -0.2794 0.9906) (xy 0.2794 0.9906)
			)
			(stroke
				(width 0)
				(type default)
			)
			(fill no)
			(layer "B.CrtYd")
		)
		(fp_line
			(start 0.2794 0.9906)
			(end -0.2794 0.9906)
			(stroke
				(width 0.1)
				(type default)
			)
			(layer "B.Fab")
		)
		(fp_line
			(start 0.2794 -0.1016)
			(end 0.2794 0.9906)
			(stroke
				(width 0.1)
				(type default)
			)
			(layer "B.Fab")
		)
		(fp_line
			(start -0.2794 0.9906)
			(end -0.2794 -0.1016)
			(stroke
				(width 0.1)
				(type default)
			)
			(layer "B.Fab")
		)
		(fp_line
			(start -0.2794 -0.1016)
			(end 0.2794 -0.1016)
			(stroke
				(width 0.1)
				(type default)
			)
			(layer "B.Fab")
		)
		(pad "1" smd rect
			(at 0 0)
			(size 0.508 0.508)
			(layers "B.Cu" "B.Mask" "B.Paste")
			(net "P3V3_STBY")
		)
		(pad "2" smd rect
			(at 0 0.889)
			(size 0.508 0.508)
			(layers "B.Cu" "B.Mask" "B.Paste")
			(net "FM_INTRUDER_HDR_PCH_N")
		)
		(zone
			(layer "B.Cu")
			(hatch none 0.5)
			(connect_pads
				(clearance 0)
			)
			(min_thickness 0.25)
			(keepout
				(tracks not_allowed)
				(vias allowed)
				(pads allowed)
				(copperpour not_allowed)
				(footprints allowed)
			)
			(placement
				(enabled no)
				(sheetname "")
			)
			(fill
				(thermal_gap 0.5)
				(thermal_bridge_width 0.5)
				(island_removal_mode 0)
			)
			(polygon
				(pts
					(xy 385.826 -87.9475) (xy 386.334 -87.9475) (xy 386.334 -87.5665) (xy 385.826 -87.5665)
				)
			)
		)
		(zone
			(layer "B.Cu")
			(hatch none 0.5)
			(connect_pads
				(clearance 0)
			)
			(min_thickness 0.25)
			(keepout
				(tracks allowed)
				(vias not_allowed)
				(pads allowed)
				(copperpour not_allowed)
				(footprints allowed)
			)
			(placement
				(enabled no)
				(sheetname "")
			)
			(fill
				(thermal_gap 0.5)
				(thermal_bridge_width 0.5)
				(island_removal_mode 0)
			)
			(polygon
				(pts
					(xy 385.826 -87.5665) (xy 386.334 -87.5665) (xy 386.334 -87.9475) (xy 385.826 -87.9475)
				)
			)
		)
	)
	(footprint ""
		(layer "B.Cu")
		(at 322.0847 -27.34818 -90)
		(property "Reference" "R4T10"
			(at 0 0 90)
			(layer "B.SilkS")
			(hide yes)
			(effects
				(font
					(size 1.27 1.27)
				)
				(justify mirror)
			)
		)
		(property "Value" ""
			(at 0 0 90)
			(layer "B.Fab")
			(effects
				(font
					(size 1.27 1.27)
				)
				(justify mirror)
			)
		)
		(duplicate_pad_numbers_are_jumpers no)
		(fp_poly
			(pts
				(xy 0.2794 -0.1016) (xy -0.2794 -0.1016) (xy -0.2794 0.9906) (xy 0.2794 0.9906)
			)
			(stroke
				(width 0)
				(type default)
			)
			(fill no)
			(layer "B.CrtYd")
		)
		(fp_line
			(start -0.2794 0.9906)
			(end -0.2794 -0.1016)
			(stroke
				(width 0.1)
				(type default)
			)
			(layer "B.Fab")
		)
		(fp_line
			(start 0.2794 0.9906)
			(end -0.2794 0.9906)
			(stroke
				(width 0.1)
				(type default)
			)
			(layer "B.Fab")
		)
		(fp_line
			(start -0.2794 -0.1016)
			(end 0.2794 -0.1016)
			(stroke
				(width 0.1)
				(type default)
			)
			(layer "B.Fab")
		)
		(fp_line
			(start 0.2794 -0.1016)
			(end 0.2794 0.9906)
			(stroke
				(width 0.1)
				(type default)
			)
			(layer "B.Fab")
		)
		(pad "1" smd rect
			(at 0 0 90)
			(size 0.508 0.508)
			(layers "B.Cu" "B.Mask" "B.Paste")
			(net "SMB_DDR_ABC_VPP_SDA_R")
		)
		(pad "2" smd rect
			(at 0 0.889 90)
			(size 0.508 0.508)
			(layers "B.Cu" "B.Mask" "B.Paste")
			(net "SMB_DDR_ABC_VPP_SDA")
		)
		(zone
			(layer "B.Cu")
			(hatch none 0.5)
			(connect_pads
				(clearance 0)
			)
			(min_thickness 0.25)
			(keepout
				(tracks not_allowed)
				(vias allowed)
				(pads allowed)
				(copperpour not_allowed)
				(footprints allowed)
			)
			(placement
				(enabled no)
				(sheetname "")
			)
			(fill
				(thermal_gap 0.5)
				(thermal_bridge_width 0.5)
				(island_removal_mode 0)
			)
			(polygon
				(pts
					(xy 321.4497 -27.09418) (xy 321.4497 -27.60218) (xy 321.8307 -27.60218) (xy 321.8307 -27.09418)
				)
			)
		)
		(zone
			(layer "B.Cu")
			(hatch none 0.5)
			(connect_pads
				(clearance 0)
			)
			(min_thickness 0.25)
			(keepout
				(tracks allowed)
				(vias not_allowed)
				(pads allowed)
				(copperpour not_allowed)
				(footprints allowed)
			)
			(placement
				(enabled no)
				(sheetname "")
			)
			(fill
				(thermal_gap 0.5)
				(thermal_bridge_width 0.5)
				(island_removal_mode 0)
			)
			(polygon
				(pts
					(xy 321.8307 -27.09418) (xy 321.8307 -27.60218) (xy 321.4497 -27.60218) (xy 321.4497 -27.09418)
				)
			)
		)
	)
	(footprint ""
		(layer "B.Cu")
		(at 1.38176 -5.35686 90)
		(property "Reference" "CT30"
			(at 0.43307 14.8844 180)
			(unlocked yes)
			(layer "B.SilkS")
			(effects
				(font
					(size 0.7874 0.5842)
					(thickness 0.1524)
				)
				(justify left mirror)
			)
		)
		(property "Value" ""
			(at 0 0 90)
			(layer "B.Fab")
			(effects
				(font
					(size 1.27 1.27)
				)
				(justify mirror)
			)
		)
		(duplicate_pad_numbers_are_jumpers no)
		(fp_rect
			(start -0.3048 -0.1016)
			(end 0.3048 0.9906)
			(stroke
				(width 0)
				(type default)
			)
			(fill no)
			(layer "B.CrtYd")
		)
		(fp_line
			(start 0.3048 -0.1016)
			(end 0.3048 0.9906)
			(stroke
				(width 0.1)
				(type default)
			)
			(layer "B.Fab")
		)
		(fp_line
			(start -0.3048 -0.1016)
			(end 0.3048 -0.1016)
			(stroke
				(width 0.1)
				(type default)
			)
			(layer "B.Fab")
		)
		(fp_line
			(start 0.3048 0.9906)
			(end -0.3048 0.9906)
			(stroke
				(width 0.1)
				(type default)
			)
			(layer "B.Fab")
		)
		(fp_line
			(start -0.3048 0.9906)
			(end -0.3048 -0.1016)
			(stroke
				(width 0.1)
				(type default)
			)
			(layer "B.Fab")
		)
		(pad "1" smd rect
			(at 0 0 270)
			(size 0.508 0.508)
			(layers "B.Cu" "B.Mask" "B.Paste")
			(net "VR_PVDDQ_GHJ_AIREF1")
		)
		(pad "2" smd rect
			(at 0 0.889 270)
			(size 0.508 0.508)
			(layers "B.Cu" "B.Mask" "B.Paste")
			(net "GND")
		)
		(zone
			(layer "B.Cu")
			(hatch none 0.5)
			(connect_pads
				(clearance 0)
			)
			(min_thickness 0.25)
			(keepout
				(tracks allowed)
				(vias not_allowed)
				(pads allowed)
				(copperpour not_allowed)
				(footprints allowed)
			)
			(placement
				(enabled no)
				(sheetname "")
			)
			(fill
				(thermal_gap 0.5)
				(thermal_bridge_width 0.5)
				(island_removal_mode 0)
			)
			(polygon
				(pts
					(xy 1.63576 -5.10286) (xy 2.01676 -5.10286) (xy 2.01676 -5.61086) (xy 1.63576 -5.61086)
				)
			)
		)
		(zone
			(layer "B.Cu")
			(hatch none 0.5)
			(connect_pads
				(clearance 0)
			)
			(min_thickness 0.25)
			(keepout
				(tracks not_allowed)
				(vias allowed)
				(pads allowed)
				(copperpour not_allowed)
				(footprints allowed)
			)
			(placement
				(enabled no)
				(sheetname "")
			)
			(fill
				(thermal_gap 0.5)
				(thermal_bridge_width 0.5)
				(island_removal_mode 0)
			)
			(polygon
				(pts
					(xy 1.63576 -5.10286) (xy 2.01676 -5.10286) (xy 2.01676 -5.61086) (xy 1.63576 -5.61086)
				)
			)
		)
	)
	(footprint ""
		(layer "B.Cu")
		(at 293.881302 -65.417192)
		(property "Reference" "R4P24"
			(at 0 0 0)
			(layer "B.SilkS")
			(hide yes)
			(effects
				(font
					(size 1.27 1.27)
				)
				(justify mirror)
			)
		)
		(property "Value" ""
			(at 0 0 0)
			(layer "B.Fab")
			(effects
				(font
					(size 1.27 1.27)
				)
				(justify mirror)
			)
		)
		(duplicate_pad_numbers_are_jumpers no)
		(fp_rect
			(start 0.2794 -0.1016)
			(end -0.2794 0.9906)
			(stroke
				(width 0)
				(type default)
			)
			(fill no)
			(layer "B.CrtYd")
		)
		(fp_line
			(start -0.2794 -0.1016)
			(end 0.2794 -0.1016)
			(stroke
				(width 0.1)
				(type default)
			)
			(layer "B.Fab")
		)
		(fp_line
			(start -0.2794 0.9906)
			(end -0.2794 -0.1016)
			(stroke
				(width 0.1)
				(type default)
			)
			(layer "B.Fab")
		)
		(fp_line
			(start 0.2794 -0.1016)
			(end 0.2794 0.9906)
			(stroke
				(width 0.1)
				(type default)
			)
			(layer "B.Fab")
		)
		(fp_line
			(start 0.2794 0.9906)
			(end -0.2794 0.9906)
			(stroke
				(width 0.1)
				(type default)
			)
			(layer "B.Fab")
		)
		(pad "1" smd rect
			(at 0 0 180)
			(size 0.508 0.508)
			(layers "B.Cu" "B.Mask" "B.Paste")
			(net "PVCCIO_CPU0")
		)
		(pad "2" smd rect
			(at 0 0.889 180)
			(size 0.508 0.508)
			(layers "B.Cu" "B.Mask" "B.Paste")
			(net "XDP_CPU_TDI")
		)
		(zone
			(layer "B.Cu")
			(hatch none 0.5)
			(connect_pads
				(clearance 0)
			)
			(min_thickness 0.25)
			(keepout
				(tracks not_allowed)
				(vias allowed)
				(pads allowed)
				(copperpour not_allowed)
				(footprints allowed)
			)
			(placement
				(enabled no)
				(sheetname "")
			)
			(fill
				(thermal_gap 0.5)
				(thermal_bridge_width 0.5)
				(island_removal_mode 0)
			)
			(polygon
				(pts
					(xy 294.135302 -65.163192) (xy 293.627302 -65.163192) (xy 293.627302 -64.782192) (xy 294.135302 -64.782192)
				)
			)
		)
		(zone
			(layer "B.Cu")
			(hatch none 0.5)
			(connect_pads
				(clearance 0)
			)
			(min_thickness 0.25)
			(keepout
				(tracks allowed)
				(vias not_allowed)
				(pads allowed)
				(copperpour not_allowed)
				(footprints allowed)
			)
			(placement
				(enabled no)
				(sheetname "")
			)
			(fill
				(thermal_gap 0.5)
				(thermal_bridge_width 0.5)
				(island_removal_mode 0)
			)
			(polygon
				(pts
					(xy 294.135302 -65.163192) (xy 293.627302 -65.163192) (xy 293.627302 -64.782192) (xy 294.135302 -64.782192)
				)
			)
		)
	)
)
